# S9S_MB_2U (Grand Teton) — schematic netlist excerpt (pin names and nets, part order shuffled) for the footprints in the layout excerpt that follows; sources: Cadence DE-HDL packaged netlist, KiCad conversion of 03242023_DA0F0TMBIJ0_F0T_Motherboard_J_brd_V01_OCP.brd

J108  CONN112_10137002101LF  CONN112_10137002-101LF IO  pkg HSD_F112D8_P2W1-2_RDH  page 139
  A1  = GPU_3V3IO_RSVD3_FFU
  A2  = GND
  A3  = PRSNT_CABLE_GPU_A2_N
  A4  = GND
  A5  = GPU_3V3IO_RSVD5_FFU
  A6  = GND
  A7  = GPU_FPGA_OVERT_N
  A8  = GND
  B1  = GND
  B2  = P5E_CPU0_PE0_RX_DN<14>
  B3  = GND
  B4  = P5E_CPU0_PE0_RX_DN<12>
  B5  = GND
  B6  = P5E_CPU0_PE0_RX_DN<10>
  B7  = GND
  B8  = P5E_CPU0_PE0_RX_DN<8>
  C1  = P5E_CPU0_PE0_RX_DN<15>
  C2  = P5E_CPU0_PE0_RX_DP<14>
  C3  = P5E_CPU0_PE0_RX_DN<13>
  C4  = P5E_CPU0_PE0_RX_DP<12>
  C5  = P5E_CPU0_PE0_RX_DP<11>
  C6  = P5E_CPU0_PE0_RX_DP<10>
  C7  = P5E_CPU0_PE0_RX_DN<9>
  C8  = P5E_CPU0_PE0_RX_DP<8>
  D1  = P5E_CPU0_PE0_RX_DP<15>
  D2  = GND
  D3  = P5E_CPU0_PE0_RX_DP<13>
  D4  = GND
  D5  = P5E_CPU0_PE0_RX_DN<11>
  D6  = GND
  D7  = P5E_CPU0_PE0_RX_DP<9>
  D8  = GND
  E1  = GND
  E2  = P5E_CPU0_PE4_RX_DP<1>
  E3  = GND
  E4  = P5E_CPU0_PE4_RX_DP<3>
  E5  = GND
  E6  = P5E_CPU0_PE4_RX_DP<5>
  E7  = GND
  E8  = P5E_CPU0_PE4_RX_DP<7>
  F1  = P5E_CPU0_PE4_RX_DN<0>
  F2  = P5E_CPU0_PE4_RX_DN<1>
  F3  = P5E_CPU0_PE4_RX_DN<2>
  F4  = P5E_CPU0_PE4_RX_DN<3>
  F5  = P5E_CPU0_PE4_RX_DN<4>
  F6  = P5E_CPU0_PE4_RX_DN<5>
  F7  = P5E_CPU0_PE4_RX_DN<6>
  F8  = P5E_CPU0_PE4_RX_DN<7>
  G1  = P5E_CPU0_PE4_RX_DP<0>
  G2  = GND
  G3  = P5E_CPU0_PE4_RX_DP<2>
  G4  = GND
  G5  = P5E_CPU0_PE4_RX_DP<4>
  G6  = GND
  G7  = P5E_CPU0_PE4_RX_DP<6>
  G8  = GND
  H1  = GND
  H2  = P5E_CPU0_PE0_TX_C_DN<14>
  H3  = GND
  H4  = P5E_CPU0_PE0_TX_C_DN<12>
  H5  = GND
  H6  = P5E_CPU0_PE0_TX_C_DN<10>
  H7  = GND
  H8  = P5E_CPU0_PE0_TX_C_DN<8>
  I1  = P5E_CPU0_PE0_TX_C_DN<15>
  I2  = P5E_CPU0_PE0_TX_C_DP<14>
  I3  = P5E_CPU0_PE0_TX_C_DN<13>
  I4  = P5E_CPU0_PE0_TX_C_DP<12>
  I5  = P5E_CPU0_PE0_TX_C_DN<11>
  I6  = P5E_CPU0_PE0_TX_C_DP<10>
  I7  = P5E_CPU0_PE0_TX_C_DN<9>
  I8  = P5E_CPU0_PE0_TX_C_DP<8>
  J1  = P5E_CPU0_PE0_TX_C_DP<15>
  J2  = GND
  J3  = P5E_CPU0_PE0_TX_C_DP<13>
  J4  = GND
  J5  = P5E_CPU0_PE0_TX_C_DP<11>
  J6  = GND
  J7  = P5E_CPU0_PE0_TX_C_DP<9>
  J8  = GND
  K1  = GND
  K2  = P5E_CPU0_PE4_TX_C_DP<1>
  K3  = GND
  K4  = P5E_CPU0_PE4_TX_C_DN<3>
  K5  = GND
  K6  = P5E_CPU0_PE4_TX_C_DN<5>
  K7  = GND
  K8  = P5E_CPU0_PE4_TX_C_DN<7>
  L1  = P5E_CPU0_PE4_TX_C_DN<0>
  L2  = P5E_CPU0_PE4_TX_C_DN<1>
  L3  = P5E_CPU0_PE4_TX_C_DN<2>
  L4  = P5E_CPU0_PE4_TX_C_DP<3>
  L5  = P5E_CPU0_PE4_TX_C_DN<4>
  L6  = P5E_CPU0_PE4_TX_C_DP<5>
  L7  = P5E_CPU0_PE4_TX_C_DN<6>
  L8  = P5E_CPU0_PE4_TX_C_DP<7>
  M1  = P5E_CPU0_PE4_TX_C_DP<0>
  M2  = GND
  M3  = P5E_CPU0_PE4_TX_C_DP<2>
  M4  = GND
  M5  = P5E_CPU0_PE4_TX_C_DP<4>
  M6  = GND
  M7  = P5E_CPU0_PE4_TX_C_DP<6>
  M8  = GND
  N1  = GND
  N2  = NC_J108_N2
  N3  = GND
  N4  = NC_J108_N4
  N5  = GND
  N6  = NC_J108_N6
  N7  = GND
  N8  = PRSNT_CABLE_GPU_A3_N

(kicad_pcb
	(version 20260206)
	(generator "pcbnew")
	(generator_version "10.0")
	(general
		(thickness 1.6)
		(legacy_teardrops no)
	)
	(paper "A4")
	(title_block
		(title "03242023_DA0F0TMBIJ0_F0T_Motherboard_J_brd_V01_OCP.brd")
		(comment 1 "Grand Teton / footprint 2591 of 6105 (J108), pads 1-31 of 48")
	)
	(layers
		(0 "F.Cu" signal "TOP")
		(4 "In1.Cu" signal "GND")
		(6 "In2.Cu" signal "IN1")
		(8 "In3.Cu" signal "GND1")
		(10 "In4.Cu" signal "IN2")
		(12 "In5.Cu" signal "GND2")
		(14 "In6.Cu" signal "IN3")
		(16 "In7.Cu" signal "GND3")
		(18 "In8.Cu" signal "VCC")
		(20 "In9.Cu" signal "VCC1")
		(22 "In10.Cu" signal "GND4")
		(24 "In11.Cu" signal "IN4")
		(26 "In12.Cu" signal "GND5")
		(28 "In13.Cu" signal "IN5")
		(30 "In14.Cu" signal "GND6")
		(32 "In15.Cu" signal "IN6")
		(34 "In16.Cu" signal "GND7")
		(2 "B.Cu" signal "BOTTOM")
		(9 "F.Adhes" user "F.Adhesive")
		(11 "B.Adhes" user "B.Adhesive")
		(13 "F.Paste" user "Package Geometry/Pastemask Top")
		(15 "B.Paste" user "Package Geometry/Pastemask Bottom")
		(5 "F.SilkS" user "Ref Des/Silkscreen Top")
		(7 "B.SilkS" user "Ref Des/Silkscreen Bottom")
		(1 "F.Mask" user "Board Geometry/Soldermask Top")
		(3 "B.Mask" user "Board Geometry/Soldermask Bottom")
		(17 "Dwgs.User" user "User.Drawings")
		(19 "Cmts.User" user "User.Comments")
		(21 "Eco1.User" user "User.Eco1")
		(23 "Eco2.User" user "User.Eco2")
		(25 "Edge.Cuts" user "Board Geometry/Outline")
		(27 "Margin" user)
		(31 "F.CrtYd" user "Package Geometry/Place Bound Top")
		(29 "B.CrtYd" user "Package Geometry/Place Bound Bottom")
		(35 "F.Fab" user "Ref Des/Assembly Top")
		(33 "B.Fab" user "Ref Des/Assembly Bottom")
	)
	(footprint ""
		(layer "F.Cu")
		(at 314.65012 -440.489848)
		(property "Reference" "J108"
			(at 12.6238 23.28799 0)
			(unlocked yes)
			(layer "F.SilkS")
			(effects
				(font
					(size 0.7874 0.5842)
					(thickness 0.1524)
				)
				(justify left)
			)
		)
		(property "Value" ""
			(at 0 0 0)
			(layer "F.Fab")
			(effects
				(font
					(size 1.27 1.27)
				)
			)
		)
		(duplicate_pad_numbers_are_jumpers no)
		(pad "A1" thru_hole rect
			(at 0 0 180)
			(size 0.766318 0.766318)
			(drill 0.359918)
			(layers "*.Cu" "*.Mask")
			(remove_unused_layers no)
			(net "GPU_3V3IO_RSVD3_FFU")
			(clearance 0.0508)
			(thermal_gap 0.0508)
			(padstack
				(mode front_inner_back)
				(layer "Inner"
					(shape circle)
					(size 0.766318 0.766318)
					(clearance 0.0508)
				)
				(layer "B.Cu"
					(shape rect)
					(size 0.766318 0.766318)
					(clearance 0.0508)
				)
			)
		)
		(pad "A2" thru_hole circle
			(at 1.999996 0.199898 180)
			(size 0.906272 0.906272)
			(drill 0.499872)
			(layers "*.Cu" "*.Mask")
			(remove_unused_layers no)
			(net "GND")
			(clearance 0.0508)
			(thermal_gap 0.0508)
		)
		(pad "A3" thru_hole circle
			(at 3.999992 0 180)
			(size 0.766318 0.766318)
			(drill 0.359918)
			(layers "*.Cu" "*.Mask")
			(remove_unused_layers no)
			(net "PRSNT_CABLE_GPU_A2_N")
			(clearance 0.0508)
			(thermal_gap 0.0508)
		)
		(pad "A4" thru_hole circle
			(at 5.999988 0.199898 180)
			(size 0.906272 0.906272)
			(drill 0.499872)
			(layers "*.Cu" "*.Mask")
			(remove_unused_layers no)
			(net "GND")
			(clearance 0.0508)
			(thermal_gap 0.0508)
		)
		(pad "A5" thru_hole circle
			(at 7.999984 0 180)
			(size 0.766318 0.766318)
			(drill 0.359918)
			(layers "*.Cu" "*.Mask")
			(remove_unused_layers no)
			(net "GPU_3V3IO_RSVD5_FFU")
			(clearance 0.0508)
			(thermal_gap 0.0508)
		)
		(pad "A6" thru_hole circle
			(at 9.99998 0.199898 180)
			(size 0.906272 0.906272)
			(drill 0.499872)
			(layers "*.Cu" "*.Mask")
			(remove_unused_layers no)
			(net "GND")
			(clearance 0.0508)
			(thermal_gap 0.0508)
		)
		(pad "A7" thru_hole circle
			(at 11.999976 0 180)
			(size 0.766318 0.766318)
			(drill 0.359918)
			(layers "*.Cu" "*.Mask")
			(remove_unused_layers no)
			(net "GPU_FPGA_OVERT_N")
			(clearance 0.0508)
			(thermal_gap 0.0508)
		)
		(pad "A8" thru_hole circle
			(at 13.999972 0.199898 180)
			(size 0.906272 0.906272)
			(drill 0.499872)
			(layers "*.Cu" "*.Mask")
			(remove_unused_layers no)
			(net "GND")
			(clearance 0.0508)
			(thermal_gap 0.0508)
		)
		(pad "B1" thru_hole circle
			(at 0 1.199896 180)
			(size 0.906272 0.906272)
			(drill 0.499872)
			(layers "*.Cu" "*.Mask")
			(remove_unused_layers no)
			(net "GND")
			(clearance 0.0508)
			(thermal_gap 0.0508)
		)
		(pad "B3" thru_hole circle
			(at 3.999992 1.199896 180)
			(size 0.906272 0.906272)
			(drill 0.499872)
			(layers "*.Cu" "*.Mask")
			(remove_unused_layers no)
			(net "GND")
			(clearance 0.0508)
			(thermal_gap 0.0508)
		)
		(pad "B5" thru_hole circle
			(at 7.999984 1.199896 180)
			(size 0.906272 0.906272)
			(drill 0.499872)
			(layers "*.Cu" "*.Mask")
			(remove_unused_layers no)
			(net "GND")
			(clearance 0.0508)
			(thermal_gap 0.0508)
		)
		(pad "B7" thru_hole circle
			(at 11.999976 1.199896 180)
			(size 0.906272 0.906272)
			(drill 0.499872)
			(layers "*.Cu" "*.Mask")
			(remove_unused_layers no)
			(net "GND")
			(clearance 0.0508)
			(thermal_gap 0.0508)
		)
		(pad "D2" thru_hole circle
			(at 1.999996 3.800094 180)
			(size 0.906272 0.906272)
			(drill 0.499872)
			(layers "*.Cu" "*.Mask")
			(remove_unused_layers no)
			(net "GND")
			(clearance 0.0508)
			(thermal_gap 0.0508)
		)
		(pad "D4" thru_hole circle
			(at 5.999988 3.800094 180)
			(size 0.906272 0.906272)
			(drill 0.499872)
			(layers "*.Cu" "*.Mask")
			(remove_unused_layers no)
			(net "GND")
			(clearance 0.0508)
			(thermal_gap 0.0508)
		)
		(pad "D6" thru_hole circle
			(at 9.99998 3.800094 180)
			(size 0.906272 0.906272)
			(drill 0.499872)
			(layers "*.Cu" "*.Mask")
			(remove_unused_layers no)
			(net "GND")
			(clearance 0.0508)
			(thermal_gap 0.0508)
		)
		(pad "D8" thru_hole circle
			(at 13.999972 3.800094 180)
			(size 0.906272 0.906272)
			(drill 0.499872)
			(layers "*.Cu" "*.Mask")
			(remove_unused_layers no)
			(net "GND")
			(clearance 0.0508)
			(thermal_gap 0.0508)
		)
		(pad "E1" thru_hole circle
			(at 0 4.800092 180)
			(size 0.906272 0.906272)
			(drill 0.499872)
			(layers "*.Cu" "*.Mask")
			(remove_unused_layers no)
			(net "GND")
			(clearance 0.0508)
			(thermal_gap 0.0508)
		)
		(pad "E3" thru_hole circle
			(at 3.999992 4.800092 180)
			(size 0.906272 0.906272)
			(drill 0.499872)
			(layers "*.Cu" "*.Mask")
			(remove_unused_layers no)
			(net "GND")
			(clearance 0.0508)
			(thermal_gap 0.0508)
		)
		(pad "E5" thru_hole circle
			(at 7.999984 4.800092 180)
			(size 0.906272 0.906272)
			(drill 0.499872)
			(layers "*.Cu" "*.Mask")
			(remove_unused_layers no)
			(net "GND")
			(clearance 0.0508)
			(thermal_gap 0.0508)
		)
		(pad "E7" thru_hole circle
			(at 11.999976 4.800092 180)
			(size 0.906272 0.906272)
			(drill 0.499872)
			(layers "*.Cu" "*.Mask")
			(remove_unused_layers no)
			(net "GND")
			(clearance 0.0508)
			(thermal_gap 0.0508)
		)
		(pad "G2" thru_hole circle
			(at 1.999996 7.400036 180)
			(size 0.906272 0.906272)
			(drill 0.499872)
			(layers "*.Cu" "*.Mask")
			(remove_unused_layers no)
			(net "GND")
			(clearance 0.0508)
			(thermal_gap 0.0508)
		)
		(pad "G4" thru_hole circle
			(at 5.999988 7.400036 180)
			(size 0.906272 0.906272)
			(drill 0.499872)
			(layers "*.Cu" "*.Mask")
			(remove_unused_layers no)
			(net "GND")
			(clearance 0.0508)
			(thermal_gap 0.0508)
		)
		(pad "G6" thru_hole circle
			(at 9.99998 7.400036 180)
			(size 0.906272 0.906272)
			(drill 0.499872)
			(layers "*.Cu" "*.Mask")
			(remove_unused_layers no)
			(net "GND")
			(clearance 0.0508)
			(thermal_gap 0.0508)
		)
		(pad "G8" thru_hole circle
			(at 13.999972 7.400036 180)
			(size 0.906272 0.906272)
			(drill 0.499872)
			(layers "*.Cu" "*.Mask")
			(remove_unused_layers no)
			(net "GND")
			(clearance 0.0508)
			(thermal_gap 0.0508)
		)
		(pad "H1" thru_hole circle
			(at 0 8.400034 180)
			(size 0.906272 0.906272)
			(drill 0.499872)
			(layers "*.Cu" "*.Mask")
			(remove_unused_layers no)
			(net "GND")
			(clearance 0.0508)
			(thermal_gap 0.0508)
		)
		(pad "H3" thru_hole circle
			(at 3.999992 8.400034 180)
			(size 0.906272 0.906272)
			(drill 0.499872)
			(layers "*.Cu" "*.Mask")
			(remove_unused_layers no)
			(net "GND")
			(clearance 0.0508)
			(thermal_gap 0.0508)
		)
		(pad "H5" thru_hole circle
			(at 7.999984 8.400034 180)
			(size 0.906272 0.906272)
			(drill 0.499872)
			(layers "*.Cu" "*.Mask")
			(remove_unused_layers no)
			(net "GND")
			(clearance 0.0508)
			(thermal_gap 0.0508)
		)
		(pad "H7" thru_hole circle
			(at 11.999976 8.400034 180)
			(size 0.906272 0.906272)
			(drill 0.499872)
			(layers "*.Cu" "*.Mask")
			(remove_unused_layers no)
			(net "GND")
			(clearance 0.0508)
			(thermal_gap 0.0508)
		)
		(pad "J2" thru_hole circle
			(at 1.999996 10.999978 180)
			(size 0.906272 0.906272)
			(drill 0.499872)
			(layers "*.Cu" "*.Mask")
			(remove_unused_layers no)
			(net "GND")
			(clearance 0.0508)
			(thermal_gap 0.0508)
		)
		(pad "J4" thru_hole circle
			(at 5.999988 10.999978 180)
			(size 0.906272 0.906272)
			(drill 0.499872)
			(layers "*.Cu" "*.Mask")
			(remove_unused_layers no)
			(net "GND")
			(clearance 0.0508)
			(thermal_gap 0.0508)
		)
		(pad "J6" thru_hole circle
			(at 9.99998 10.999978 180)
			(size 0.906272 0.906272)
			(drill 0.499872)
			(layers "*.Cu" "*.Mask")
			(remove_unused_layers no)
			(net "GND")
			(clearance 0.0508)
			(thermal_gap 0.0508)
		)
	)
)
